(kicad_pcb
	(version 20221018)
	(generator pcbnew)
	(general
    (thickness 1.6)
  )
	(paper "A4")
	(title_block
    (title "NUC Computer Cluster Power Breakout HW")
    (date "2023-10-18")
    (rev "1.4.3")
    (company "Antmicro Ltd.")
		(comment 9 "footprints 93-102 of 234")
	)
	(layers
    (0 "F.Cu" mixed)
    (1 "In1.Cu" power)
    (2 "In2.Cu" mixed)
    (31 "B.Cu" power)
    (32 "B.Adhes" user "B.Adhesive")
    (33 "F.Adhes" user "F.Adhesive")
    (34 "B.Paste" user)
    (35 "F.Paste" user)
    (36 "B.SilkS" user "B.Silkscreen")
    (37 "F.SilkS" user "F.Silkscreen")
    (38 "B.Mask" user)
    (39 "F.Mask" user)
    (40 "Dwgs.User" user "User.Drawings")
    (41 "Cmts.User" user "User.Comments")
    (42 "Eco1.User" user "User.Eco1")
    (43 "Eco2.User" user "User.Eco2")
    (44 "Edge.Cuts" user)
    (45 "Margin" user)
    (46 "B.CrtYd" user "B.Courtyard")
    (47 "F.CrtYd" user "F.Courtyard")
    (48 "B.Fab" user)
    (49 "F.Fab" user)
  )
	(footprint "antmicro-footprints:TP_SMD_1mm" (layer "F.Cu")
    (at 114.3 131.4 -90)
    (property "Author" "Antmicro")
    (property "License" "Apache-2.0")
    (property "MPN" "")
    (property "Manufacturer" "")
    (property "Sheetfile" "d1600e-psu-breakout-board.kicad_sch")
    (property "Sheetname" "")
    (property "exclude_from_bom" "")
    (property "ki_description" "Test point 1mm SMD")
    (property "ki_keywords" "TESTPOINT")
    (attr exclude_from_pos_files exclude_from_bom)
    (fp_text reference "TP_S17" (at -0.7 -0.45 -90) (layer "F.SilkS")
        (effects (font (size 0.7 0.7) (thickness 0.15)) (justify left bottom))
    )
    (fp_text value "TP_1mm_SMD" (at 0 1.4 -90) (layer "F.Fab")
        (effects (font (size 0.7 0.7) (thickness 0.15)) (justify left bottom))
    )
    (fp_text user "Author: Antmicro" (at -0.5 4 -90) (layer "F.Fab") hide
        (effects (font (size 0.7 0.7) (thickness 0.15)) (justify left bottom))
    )
    (fp_text user "${REFERENCE}" (at -0.5 2.8 -90) (layer "F.Fab") hide
        (effects (font (size 0.7 0.7) (thickness 0.15)) (justify left bottom))
    )
    (fp_text user "License: Apache-2.0" (at -0.5 5.2 -90) (layer "F.Fab") hide
        (effects (font (size 0.7 0.7) (thickness 0.15)) (justify left bottom))
    )
    (fp_circle (center 0 0) (end 0.6 0)
      (stroke (width 0.05) (type default)) (fill none) (layer "F.CrtYd"))
    (pad "1" smd circle (at 0 0 270) (size 1 1) (layers "F.Cu" "F.Mask")
      (net 72 "Net-(J10-PadS17)") (pinfunction "1") (pintype "passive"))
  )
	(footprint "antmicro-footprints:TP_SMD_1mm" (layer "F.Cu")
    (at 113 131.4 -90)
    (property "Author" "Antmicro")
    (property "License" "Apache-2.0")
    (property "MPN" "")
    (property "Manufacturer" "")
    (property "Sheetfile" "d1600e-psu-breakout-board.kicad_sch")
    (property "Sheetname" "")
    (property "exclude_from_bom" "")
    (property "ki_description" "Test point 1mm SMD")
    (property "ki_keywords" "TESTPOINT")
    (attr exclude_from_pos_files exclude_from_bom)
    (fp_text reference "TP_S16" (at -0.7 -0.45 -90) (layer "F.SilkS")
        (effects (font (size 0.7 0.7) (thickness 0.15)) (justify left bottom))
    )
    (fp_text value "TP_1mm_SMD" (at 0 1.4 -90) (layer "F.Fab")
        (effects (font (size 0.7 0.7) (thickness 0.15)) (justify left bottom))
    )
    (fp_text user "Author: Antmicro" (at -0.5 4 -90) (layer "F.Fab") hide
        (effects (font (size 0.7 0.7) (thickness 0.15)) (justify left bottom))
    )
    (fp_text user "${REFERENCE}" (at -0.5 2.8 -90) (layer "F.Fab") hide
        (effects (font (size 0.7 0.7) (thickness 0.15)) (justify left bottom))
    )
    (fp_text user "License: Apache-2.0" (at -0.5 5.2 -90) (layer "F.Fab") hide
        (effects (font (size 0.7 0.7) (thickness 0.15)) (justify left bottom))
    )
    (fp_circle (center 0 0) (end 0.6 0)
      (stroke (width 0.05) (type default)) (fill none) (layer "F.CrtYd"))
    (pad "1" smd circle (at 0 0 270) (size 1 1) (layers "F.Cu" "F.Mask")
      (net 75 "Net-(J10-PadS16)") (pinfunction "1") (pintype "passive"))
  )
	(footprint "antmicro-footprints:R_0402_1005Metric" (layer "F.Cu")
    (at 131.4 92.05 180)
    (descr "Resistor SMD 0402")
    (tags "resistor SMD 0402")
    (property "Author" "Antmicro")
    (property "License" "Apache-2.0")
    (property "MPN" "CR0402-FX-4701GLF")
    (property "Manufacturer" "Bourns")
    (property "Sheetfile" "power-switch.kicad_sch")
    (property "Sheetname" "Power switch 2")
    (property "Tolerance" "1%")
    (property "Val" "4k7")
    (property "ki_description" "SMD Chip Resistor, 4.7 kohm, ± 1%, 62.5 mW, 0402 [1005 Metric], Thick Film, General Purpose")
    (property "ki_keywords" "0402, SMT, RESISTOR, PASSIVE")
    (zone_connect 1)
    (attr smd)
    (fp_text reference "R23" (at -0.45 -1.45 180) (layer "F.SilkS")
        (effects (font (size 0.7 0.7) (thickness 0.15)) (justify left bottom))
    )
    (fp_text value "R_4k7_0402" (at -1.011843 1.772047 180) (layer "F.Fab")
        (effects (font (size 0.7 0.7) (thickness 0.15)) (justify left bottom))
    )
    (fp_text user "${REFERENCE}" (at -0.95 3.168 180) (layer "F.Fab") hide
        (effects (font (size 0.7 0.7) (thickness 0.15)) (justify left bottom))
    )
    (fp_text user "License: Apache-2.0" (at -0.95 5.169 180) (layer "F.Fab") hide
        (effects (font (size 0.7 0.7) (thickness 0.15)) (justify left bottom))
    )
    (fp_text user "Author: Antmicro" (at -0.95 4.169 180) (layer "F.Fab") hide
        (effects (font (size 0.7 0.7) (thickness 0.15)) (justify left bottom))
    )
    (fp_rect (start -0.925 -0.47) (end 0.925 0.47)
      (stroke (width 0.05) (type default)) (fill none) (layer "F.CrtYd"))
    (fp_rect (start -0.5 -0.25) (end 0.5 0.25)
      (stroke (width 0.15) (type solid)) (fill none) (layer "F.Fab"))
    (pad "1" smd roundrect (at -0.48 0 180) (size 0.59 0.64) (layers "F.Cu" "F.Paste" "F.Mask") (roundrect_rratio 0.25)
      (net 11 "VCC12V0") (pintype "passive"))
    (pad "2" smd roundrect (at 0.48 0 180) (size 0.59 0.64) (layers "F.Cu" "F.Paste" "F.Mask") (roundrect_rratio 0.25)
      (net 84 "Net-(D16-A)") (pintype "passive"))
  )
	(footprint "antmicro-footprints:TP_SMD_1mm" (layer "F.Cu")
    (at 120.8508 131.4 -90)
    (property "Author" "Antmicro")
    (property "License" "Apache-2.0")
    (property "MPN" "")
    (property "Manufacturer" "")
    (property "Sheetfile" "d1600e-psu-breakout-board.kicad_sch")
    (property "Sheetname" "")
    (property "exclude_from_bom" "")
    (property "ki_description" "Test point 1mm SMD")
    (property "ki_keywords" "TESTPOINT")
    (attr exclude_from_pos_files exclude_from_bom)
    (fp_text reference "TP_S22" (at -0.7 -0.45 -90) (layer "F.SilkS")
        (effects (font (size 0.7 0.7) (thickness 0.15)) (justify left bottom))
    )
    (fp_text value "TP_1mm_SMD" (at 0 1.4 -90) (layer "F.Fab")
        (effects (font (size 0.7 0.7) (thickness 0.15)) (justify left bottom))
    )
    (fp_text user "License: Apache-2.0" (at -0.5 5.2 -90) (layer "F.Fab") hide
        (effects (font (size 0.7 0.7) (thickness 0.15)) (justify left bottom))
    )
    (fp_text user "Author: Antmicro" (at -0.5 4 -90) (layer "F.Fab") hide
        (effects (font (size 0.7 0.7) (thickness 0.15)) (justify left bottom))
    )
    (fp_text user "${REFERENCE}" (at -0.5 2.8 -90) (layer "F.Fab") hide
        (effects (font (size 0.7 0.7) (thickness 0.15)) (justify left bottom))
    )
    (fp_circle (center 0 0) (end 0.6 0)
      (stroke (width 0.05) (type default)) (fill none) (layer "F.CrtYd"))
    (pad "1" smd circle (at 0 0 270) (size 1 1) (layers "F.Cu" "F.Mask")
      (net 70 "Net-(J10-PadS22)") (pinfunction "1") (pintype "passive"))
  )
	(footprint "antmicro-footprints:TP_SMD_1mm" (layer "F.Cu")
    (at 186.2 126.7758)
    (property "Author" "Antmicro")
    (property "License" "Apache-2.0")
    (property "MPN" "")
    (property "Manufacturer" "")
    (property "Sheetfile" "ftdi-module.kicad_sch")
    (property "Sheetname" "FTDI")
    (property "exclude_from_bom" "")
    (property "ki_description" "Test point 1mm SMD")
    (property "ki_keywords" "TESTPOINT")
    (attr exclude_from_pos_files exclude_from_bom)
    (fp_text reference "3V3_USB1" (at -4.3 1.6242) (layer "F.SilkS")
        (effects (font (size 0.7 0.7) (thickness 0.15)) (justify left bottom))
    )
    (fp_text value "TP_1mm_SMD" (at 0 1.4) (layer "F.Fab")
        (effects (font (size 0.7 0.7) (thickness 0.15)) (justify left bottom))
    )
    (fp_text user "Author: Antmicro" (at -0.5 4) (layer "F.Fab") hide
        (effects (font (size 0.7 0.7) (thickness 0.15)) (justify left bottom))
    )
    (fp_text user "License: Apache-2.0" (at -0.5 5.2) (layer "F.Fab") hide
        (effects (font (size 0.7 0.7) (thickness 0.15)) (justify left bottom))
    )
    (fp_text user "${REFERENCE}" (at -0.5 2.8) (layer "F.Fab") hide
        (effects (font (size 0.7 0.7) (thickness 0.15)) (justify left bottom))
    )
    (fp_circle (center 0 0) (end 0.6 0)
      (stroke (width 0.05) (type default)) (fill none) (layer "F.CrtYd"))
    (pad "1" smd circle (at 0 0) (size 1 1) (layers "F.Cu" "F.Mask")
      (net 76 "VCC3V3_USB") (pinfunction "1") (pintype "passive"))
  )
	(footprint "antmicro-footprints:C_0402_1005Metric" (layer "F.Cu")
    (at 174.3 110.55)
    (descr "Capacitor SMD 0402")
    (tags "capacitor SMD 0402")
    (property "Author" "Antmicro")
    (property "Dielectric" "X5R")
    (property "License" "Apache-2.0")
    (property "MPN" "GRM155R61H104KE14D")
    (property "Manufacturer" "Murata")
    (property "Sheetfile" "ftdi-module.kicad_sch")
    (property "Sheetname" "FTDI")
    (property "Val" "100n")
    (property "Voltage" "50V")
    (property "ki_description" "SMD Multilayer Ceramic Capacitor, 0.1 µF, 50 V, 0402 [1005 Metric], ± 10%, X5R, GRM Series")
    (property "ki_keywords" "0402, SMT, CAPACITOR, PASSIVE, CERAMIC, MLCC")
    (attr smd)
    (fp_text reference "C16" (at -1.9 1.45) (layer "F.SilkS")
        (effects (font (size 0.7 0.7) (thickness 0.15)) (justify left bottom))
    )
    (fp_text value "C_100n_0402" (at -1.022927 2.155213) (layer "F.Fab")
        (effects (font (size 0.7 0.7) (thickness 0.15)) (justify left bottom))
    )
    (fp_text user "Author: Antmicro" (at -0.939 3.399) (layer "F.Fab") hide
        (effects (font (size 0.7 0.7) (thickness 0.15)) (justify left bottom))
    )
    (fp_text user "License: Apache-2.0" (at -0.939 5.799) (layer "F.Fab") hide
        (effects (font (size 0.7 0.7) (thickness 0.15)) (justify left bottom))
    )
    (fp_text user "${REFERENCE}" (at -0.939 4.599) (layer "F.Fab") hide
        (effects (font (size 0.7 0.7) (thickness 0.15)) (justify left bottom))
    )
    (fp_rect (start -0.925 -0.47) (end 0.925 0.47)
      (stroke (width 0.05) (type default)) (fill none) (layer "F.CrtYd"))
    (fp_line (start -0.494 -0.25) (end 0.504 -0.25)
      (stroke (width 0.15) (type solid)) (layer "F.Fab"))
    (fp_line (start -0.494 0.248) (end -0.494 -0.25)
      (stroke (width 0.15) (type solid)) (layer "F.Fab"))
    (fp_line (start 0.504 -0.25) (end 0.504 0.248)
      (stroke (width 0.15) (type solid)) (layer "F.Fab"))
    (fp_line (start 0.504 0.248) (end -0.494 0.248)
      (stroke (width 0.15) (type solid)) (layer "F.Fab"))
    (pad "1" smd roundrect (at -0.48 0) (size 0.59 0.64) (layers "F.Cu" "F.Paste" "F.Mask") (roundrect_rratio 0.25)
      (net 77 "GNDD") (pintype "passive"))
    (pad "2" smd roundrect (at 0.48 0) (size 0.59 0.64) (layers "F.Cu" "F.Paste" "F.Mask") (roundrect_rratio 0.25)
      (net 76 "VCC3V3_USB") (pintype "passive"))
  )
	(footprint "antmicro-footprints:C_0402_1005Metric" (layer "F.Cu")
    (at 181.2 117.45)
    (descr "Capacitor SMD 0402")
    (tags "capacitor SMD 0402")
    (property "Author" "Antmicro")
    (property "Dielectric" "")
    (property "License" "Apache-2.0")
    (property "MPN" "GRM155R61A475MEAAD")
    (property "Manufacturer" "Murata")
    (property "Sheetfile" "ftdi-module.kicad_sch")
    (property "Sheetname" "FTDI")
    (property "Val" "4u7")
    (property "Voltage" "")
    (property "ki_description" "SMD Multilayer Ceramic Capacitor, 4.7 µF, 10 V, 0402 [1005 Metric], ± 20%, X5R, GRM Series")
    (property "ki_keywords" "0402, SMT, CAPACITOR, PASSIVE")
    (attr smd)
    (fp_text reference "C19" (at -3.1 0.3) (layer "F.SilkS")
        (effects (font (size 0.7 0.7) (thickness 0.15)) (justify left bottom))
    )
    (fp_text value "C_4u7_0402" (at -1.022927 2.155213) (layer "F.Fab")
        (effects (font (size 0.7 0.7) (thickness 0.15)) (justify left bottom))
    )
    (fp_text user "${REFERENCE}" (at -0.939 4.599) (layer "F.Fab") hide
        (effects (font (size 0.7 0.7) (thickness 0.15)) (justify left bottom))
    )
    (fp_text user "Author: Antmicro" (at -0.939 3.399) (layer "F.Fab") hide
        (effects (font (size 0.7 0.7) (thickness 0.15)) (justify left bottom))
    )
    (fp_text user "License: Apache-2.0" (at -0.939 5.799) (layer "F.Fab") hide
        (effects (font (size 0.7 0.7) (thickness 0.15)) (justify left bottom))
    )
    (fp_rect (start -0.925 -0.47) (end 0.925 0.47)
      (stroke (width 0.05) (type default)) (fill none) (layer "F.CrtYd"))
    (fp_line (start -0.494 -0.25) (end 0.504 -0.25)
      (stroke (width 0.15) (type solid)) (layer "F.Fab"))
    (fp_line (start -0.494 0.248) (end -0.494 -0.25)
      (stroke (width 0.15) (type solid)) (layer "F.Fab"))
    (fp_line (start 0.504 -0.25) (end 0.504 0.248)
      (stroke (width 0.15) (type solid)) (layer "F.Fab"))
    (fp_line (start 0.504 0.248) (end -0.494 0.248)
      (stroke (width 0.15) (type solid)) (layer "F.Fab"))
    (pad "1" smd roundrect (at -0.48 0) (size 0.59 0.64) (layers "F.Cu" "F.Paste" "F.Mask") (roundrect_rratio 0.25)
      (net 77 "GNDD") (pintype "passive"))
    (pad "2" smd roundrect (at 0.48 0) (size 0.59 0.64) (layers "F.Cu" "F.Paste" "F.Mask") (roundrect_rratio 0.25)
      (net 3 "VCC5V0_USB") (pintype "passive"))
  )
	(footprint "antmicro-footprints:C_0402_1005Metric" (layer "F.Cu")
    (at 186.6 124.875 180)
    (descr "Capacitor SMD 0402")
    (tags "capacitor SMD 0402")
    (property "Author" "Antmicro")
    (property "Dielectric" "")
    (property "License" "Apache-2.0")
    (property "MPN" "GRM155R61A475MEAAD")
    (property "Manufacturer" "Murata")
    (property "Sheetfile" "ftdi-module.kicad_sch")
    (property "Sheetname" "FTDI")
    (property "Val" "4u7")
    (property "Voltage" "")
    (property "ki_description" "SMD Multilayer Ceramic Capacitor, 4.7 µF, 10 V, 0402 [1005 Metric], ± 20%, X5R, GRM Series")
    (property "ki_keywords" "0402, SMT, CAPACITOR, PASSIVE")
    (attr smd)
    (fp_text reference "C20" (at 0.95 -0.625) (layer "F.SilkS")
        (effects (font (size 0.7 0.7) (thickness 0.15)) (justify right bottom))
    )
    (fp_text value "C_4u7_0402" (at -1.022927 2.155213) (layer "F.Fab")
        (effects (font (size 0.7 0.7) (thickness 0.15)) (justify right bottom))
    )
    (fp_text user "License: Apache-2.0" (at -0.939 5.799) (layer "F.Fab") hide
        (effects (font (size 0.7 0.7) (thickness 0.15)) (justify right bottom))
    )
    (fp_text user "${REFERENCE}" (at -0.939 4.599) (layer "F.Fab") hide
        (effects (font (size 0.7 0.7) (thickness 0.15)) (justify right bottom))
    )
    (fp_text user "Author: Antmicro" (at -0.939 3.399) (layer "F.Fab") hide
        (effects (font (size 0.7 0.7) (thickness 0.15)) (justify right bottom))
    )
    (fp_rect (start -0.925 -0.47) (end 0.925 0.47)
      (stroke (width 0.05) (type default)) (fill none) (layer "F.CrtYd"))
    (fp_line (start -0.494 -0.25) (end 0.504 -0.25)
      (stroke (width 0.15) (type solid)) (layer "F.Fab"))
    (fp_line (start -0.494 0.248) (end -0.494 -0.25)
      (stroke (width 0.15) (type solid)) (layer "F.Fab"))
    (fp_line (start 0.504 -0.25) (end 0.504 0.248)
      (stroke (width 0.15) (type solid)) (layer "F.Fab"))
    (fp_line (start 0.504 0.248) (end -0.494 0.248)
      (stroke (width 0.15) (type solid)) (layer "F.Fab"))
    (pad "1" smd roundrect (at -0.48 0 180) (size 0.59 0.64) (layers "F.Cu" "F.Paste" "F.Mask") (roundrect_rratio 0.25)
      (net 77 "GNDD") (pintype "passive"))
    (pad "2" smd roundrect (at 0.48 0 180) (size 0.59 0.64) (layers "F.Cu" "F.Paste" "F.Mask") (roundrect_rratio 0.25)
      (net 76 "VCC3V3_USB") (pintype "passive"))
  )
	(footprint "antmicro-footprints:C_0603_1608Metric" (layer "F.Cu")
    (at 109.747132 99.826324 -90)
    (descr "Capacitor SMD 0603")
    (tags "capacitor 0603")
    (property "Author" "Antmicro")
    (property "Dielectric" "")
    (property "License" "Apache-2.0")
    (property "MPN" "C1608X5R1E106M080AC")
    (property "Manufacturer" "TDK")
    (property "Sheetfile" "daughterboard-supply.kicad_sch")
    (property "Sheetname" "daughterboard-supply")
    (property "Val" "10u")
    (property "Voltage" "25V")
    (property "ki_description" "SMD Multilayer Ceramic Capacitor, 10 µF, 25 V, 0603 [1608 Metric], ± 20%, X5R, C")
    (property "ki_keywords" "0603, SMT, CAPACITOR, PASSIVE, CERAMIC, MLCC")
    (attr smd)
    (fp_text reference "C33" (at -2.326324 -1.702868 90) (layer "F.SilkS")
        (effects (font (size 0.7 0.7) (thickness 0.15)) (justify right bottom))
    )
    (fp_text value "C_10u_25V_0603" (at -1.42757 1.770288 90) (layer "F.Fab")
        (effects (font (size 0.7 0.7) (thickness 0.15)) (justify right bottom))
    )
    (fp_text user "${REFERENCE}" (at -1.682 3.895 90) (layer "F.Fab") hide
        (effects (font (size 0.7 0.7) (thickness 0.15)) (justify right bottom))
    )
    (fp_text user "Author: Antmicro" (at -1.682 4.894 90) (layer "F.Fab") hide
        (effects (font (size 0.7 0.7) (thickness 0.15)) (justify right bottom))
    )
    (fp_text user "License: Apache-2.0" (at -1.682 5.895 90) (layer "F.Fab") hide
        (effects (font (size 0.7 0.7) (thickness 0.15)) (justify right bottom))
    )
    (fp_line (start -0.15 -0.4) (end 0.15 -0.4)
      (stroke (width 0.15) (type solid)) (layer "F.SilkS"))
    (fp_line (start -0.15 0.4) (end 0.15 0.4)
      (stroke (width 0.15) (type solid)) (layer "F.SilkS"))
    (fp_rect (start -1.25 -0.65) (end 1.25 0.65)
      (stroke (width 0.05) (type solid)) (fill none) (layer "F.CrtYd"))
    (fp_rect (start -0.8 -0.4) (end 0.8 0.4)
      (stroke (width 0.15) (type solid)) (fill none) (layer "F.Fab"))
    (pad "1" smd roundrect (at -0.7 0 270) (size 0.8 1) (layers "F.Cu" "F.Paste" "F.Mask") (roundrect_rratio 0.2)
      (net 4 "GND") (pintype "passive"))
    (pad "2" smd roundrect (at 0.7 0 270) (size 0.8 1) (layers "F.Cu" "F.Paste" "F.Mask") (roundrect_rratio 0.2)
      (net 11 "VCC12V0") (pintype "passive"))
  )
	(footprint "antmicro-footprints:C_0402_1005Metric" (layer "F.Cu")
    (at 104.647132 97.526324 -90)
    (descr "Capacitor SMD 0402")
    (tags "capacitor SMD 0402")
    (property "Author" "Antmicro")
    (property "Dielectric" "X5R")
    (property "License" "Apache-2.0")
    (property "MPN" "GRM155R61H104KE14D")
    (property "Manufacturer" "Murata")
    (property "Sheetfile" "daughterboard-supply.kicad_sch")
    (property "Sheetname" "daughterboard-supply")
    (property "Val" "100n")
    (property "Voltage" "50V")
    (property "ki_description" "SMD Multilayer Ceramic Capacitor, 0.1 µF, 50 V, 0402 [1005 Metric], ± 10%, X5R, GRM Series")
    (property "ki_keywords" "0402, SMT, CAPACITOR, PASSIVE, CERAMIC, MLCC")
    (attr smd)
    (fp_text reference "C34" (at -3.076324 -0.502868 90) (layer "F.SilkS")
        (effects (font (size 0.7 0.7) (thickness 0.15)) (justify right bottom))
    )
    (fp_text value "C_100n_0402" (at -1.022927 2.155213 90) (layer "F.Fab")
        (effects (font (size 0.7 0.7) (thickness 0.15)) (justify right bottom))
    )
    (fp_text user "${REFERENCE}" (at -0.939 4.599 90) (layer "F.Fab") hide
        (effects (font (size 0.7 0.7) (thickness 0.15)) (justify right bottom))
    )
    (fp_text user "License: Apache-2.0" (at -0.939 5.799 90) (layer "F.Fab") hide
        (effects (font (size 0.7 0.7) (thickness 0.15)) (justify right bottom))
    )
    (fp_text user "Author: Antmicro" (at -0.939 3.399 90) (layer "F.Fab") hide
        (effects (font (size 0.7 0.7) (thickness 0.15)) (justify right bottom))
    )
    (fp_rect (start -0.925 -0.47) (end 0.925 0.47)
      (stroke (width 0.05) (type default)) (fill none) (layer "F.CrtYd"))
    (fp_line (start -0.494 -0.25) (end 0.504 -0.25)
      (stroke (width 0.15) (type solid)) (layer "F.Fab"))
    (fp_line (start -0.494 0.248) (end -0.494 -0.25)
      (stroke (width 0.15) (type solid)) (layer "F.Fab"))
    (fp_line (start 0.504 -0.25) (end 0.504 0.248)
      (stroke (width 0.15) (type solid)) (layer "F.Fab"))
    (fp_line (start 0.504 0.248) (end -0.494 0.248)
      (stroke (width 0.15) (type solid)) (layer "F.Fab"))
    (pad "1" smd roundrect (at -0.48 0 270) (size 0.59 0.64) (layers "F.Cu" "F.Paste" "F.Mask") (roundrect_rratio 0.25)
      (net 16 "Net-(U4-BST)") (pintype "passive"))
    (pad "2" smd roundrect (at 0.48 0 270) (size 0.59 0.64) (layers "F.Cu" "F.Paste" "F.Mask") (roundrect_rratio 0.25)
      (net 32 "Net-(U4-SW)") (pintype "passive"))
  )
)
